(kicad_pcb
	(version 20260206)
	(generator "pcbnew")
	(generator_version "10.0")
	(general
		(thickness 1.6)
		(legacy_teardrops no)
	)
	(paper "A4")
	(title_block
		(title "dpb — 14545-sa.0730WZS0815.brd")
		(comment 1 "Honey Badger (Wiwynn) / footprints 280-286 of 1066")
	)
	(layers
		(0 "F.Cu" signal "TOP")
		(4 "In1.Cu" signal "L2GND")
		(6 "In2.Cu" signal "L3")
		(8 "In3.Cu" signal "L4VCC")
		(10 "In4.Cu" signal "L5VCC")
		(12 "In5.Cu" signal "L6")
		(14 "In6.Cu" signal "L7GND")
		(2 "B.Cu" signal "BOTTOM")
		(9 "F.Adhes" user "F.Adhesive")
		(11 "B.Adhes" user "B.Adhesive")
		(13 "F.Paste" user "Package Geometry/Pastemask Top")
		(15 "B.Paste" user "Package Geometry/Pastemask Bottom")
		(5 "F.SilkS" user "Ref Des/Silkscreen Top")
		(7 "B.SilkS" user "Ref Des/Silkscreen Bottom")
		(1 "F.Mask" user "Board Geometry/Soldermask Top")
		(3 "B.Mask" user "Board Geometry/Soldermask Bottom")
		(17 "Dwgs.User" user "User.Drawings")
		(19 "Cmts.User" user "User.Comments")
		(21 "Eco1.User" user "User.Eco1")
		(23 "Eco2.User" user "User.Eco2")
		(25 "Edge.Cuts" user "Board Geometry/Outline")
		(27 "Margin" user)
		(31 "F.CrtYd" user "Package Geometry/Place Bound Top")
		(29 "B.CrtYd" user "Package Geometry/Place Bound Bottom")
		(35 "F.Fab" user "Ref Des/Assembly Top")
		(33 "B.Fab" user "Ref Des/Assembly Bottom")
	)
	(footprint ""
		(layer "F.Cu")
		(at 216.026746 -492.8997 -90)
		(property "Reference" "R110"
			(at 0 0 270)
			(layer "F.SilkS")
			(hide yes)
			(effects
				(font
					(size 1.27 1.27)
				)
			)
		)
		(property "Value" "2R2010J-1-GP"
			(at 0.254 -8.0772 270)
			(unlocked yes)
			(layer "F.Fab")
			(hide yes)
			(effects
				(font
					(size 1.016 1.016)
					(thickness 0.1524)
				)
			)
		)
		(property "Device Type" "R2010H28"
			(at 0.254 -9.6774 270)
			(unlocked yes)
			(layer "F.Fab")
			(hide yes)
			(effects
				(font
					(size 1.016 1.016)
					(thickness 0.1524)
				)
			)
		)
		(duplicate_pad_numbers_are_jumpers no)
		(fp_line
			(start -1.651 3.302)
			(end 1.651 3.302)
			(stroke
				(width 0.1524)
				(type default)
			)
			(layer "F.SilkS")
		)
		(fp_line
			(start 1.651 3.302)
			(end 1.651 -3.302)
			(stroke
				(width 0.1524)
				(type default)
			)
			(layer "F.SilkS")
		)
		(fp_line
			(start -1.651 -3.302)
			(end -1.651 3.302)
			(stroke
				(width 0.1524)
				(type default)
			)
			(layer "F.SilkS")
		)
		(fp_line
			(start 1.651 -3.302)
			(end -1.651 -3.302)
			(stroke
				(width 0.1524)
				(type default)
			)
			(layer "F.SilkS")
		)
		(fp_rect
			(start -1.7272 -3.3782)
			(end 1.7272 3.3782)
			(stroke
				(width 0)
				(type default)
			)
			(fill no)
			(layer "F.CrtYd")
		)
		(fp_poly
			(pts
				(xy 1.7272 3.3782) (xy 1.7272 -3.3782) (xy -1.7272 -3.3782) (xy -1.7272 3.3782)
			)
			(stroke
				(width 0)
				(type default)
			)
			(fill no)
			(layer "F.Fab")
		)
		(pad "1" smd rect
			(at 0 -2.3495 270)
			(size 2.794 1.143)
			(layers "F.Cu" "F.Mask" "F.Paste")
			(net "12V_PRE_0")
		)
		(pad "2" smd rect
			(at 0 2.3495 270)
			(size 2.794 1.143)
			(layers "F.Cu" "F.Mask" "F.Paste")
			(net "P12V_HDD0")
		)
	)
	(footprint ""
		(layer "F.Cu")
		(at 193.548 -384.81)
		(property "Reference" "C117"
			(at 0 0 0)
			(layer "F.SilkS")
			(hide yes)
			(effects
				(font
					(size 1.27 1.27)
				)
			)
		)
		(property "Value" "SCD1U10V2KX-5GP"
			(at 1.1811 -2.7051 0)
			(unlocked yes)
			(layer "F.Fab")
			(hide yes)
			(effects
				(font
					(size 1.016 1.016)
					(thickness 0.1524)
				)
			)
		)
		(property "Device Type" "C402H22"
			(at 1.1811 -4.2291 0)
			(unlocked yes)
			(layer "F.Fab")
			(hide yes)
			(effects
				(font
					(size 1.016 1.016)
					(thickness 0.1524)
				)
			)
		)
		(duplicate_pad_numbers_are_jumpers no)
		(fp_rect
			(start -0.4318 0.9525)
			(end 0.4318 -0.9525)
			(stroke
				(width 0)
				(type default)
			)
			(fill no)
			(layer "F.CrtYd")
		)
		(fp_rect
			(start -0.4318 0.9525)
			(end 0.4318 -0.9525)
			(stroke
				(width 0)
				(type default)
			)
			(fill no)
			(layer "F.Fab")
		)
		(pad "1" smd custom
			(at 0 -0.4445)
			(size 0.1524 0.1524)
			(layers "F.Cu" "F.Mask" "F.Paste")
			(net "P3V3")
			(options
				(clearance outline)
				(anchor circle)
			)
			(primitives
				(gr_poly
					(pts
						(arc
							(start 0.3048 -0.2032)
							(mid 0.275042 -0.275042)
							(end 0.2032 -0.3048)
						)
						(arc
							(start -0.2032 -0.3048)
							(mid -0.275042 -0.275042)
							(end -0.3048 -0.2032)
						)
						(arc
							(start -0.3048 0.2032)
							(mid -0.275042 0.275042)
							(end -0.2032 0.3048)
						)
						(arc
							(start 0.2032 0.3048)
							(mid 0.275042 0.275042)
							(end 0.3048 0.2032)
						)
					)
					(width 0)
					(fill yes)
				)
			)
		)
		(pad "2" smd custom
			(at 0 0.4445)
			(size 0.1524 0.1524)
			(layers "F.Cu" "F.Mask" "F.Paste")
			(net "GND")
			(options
				(clearance outline)
				(anchor circle)
			)
			(primitives
				(gr_poly
					(pts
						(arc
							(start 0.3048 -0.2032)
							(mid 0.275042 -0.275042)
							(end 0.2032 -0.3048)
						)
						(arc
							(start -0.2032 -0.3048)
							(mid -0.275042 -0.275042)
							(end -0.3048 -0.2032)
						)
						(arc
							(start -0.3048 0.2032)
							(mid -0.275042 0.275042)
							(end -0.2032 0.3048)
						)
						(arc
							(start 0.2032 0.3048)
							(mid 0.275042 0.275042)
							(end 0.3048 0.2032)
						)
					)
					(width 0)
					(fill yes)
				)
			)
		)
	)
	(footprint ""
		(layer "F.Cu")
		(at 83.058 -399.415 180)
		(property "Reference" "C370"
			(at 0 0 180)
			(layer "F.SilkS")
			(hide yes)
			(effects
				(font
					(size 1.27 1.27)
				)
			)
		)
		(property "Value" "SCD033U25V2KX-GP"
			(at 1.1811 -2.7051 180)
			(unlocked yes)
			(layer "F.Fab")
			(hide yes)
			(effects
				(font
					(size 1.016 1.016)
					(thickness 0.1524)
				)
			)
		)
		(property "Device Type" "C402H22"
			(at 1.1811 -4.2291 180)
			(unlocked yes)
			(layer "F.Fab")
			(hide yes)
			(effects
				(font
					(size 1.016 1.016)
					(thickness 0.1524)
				)
			)
		)
		(duplicate_pad_numbers_are_jumpers no)
		(fp_rect
			(start -0.4318 0.9525)
			(end 0.4318 -0.9525)
			(stroke
				(width 0)
				(type default)
			)
			(fill no)
			(layer "F.CrtYd")
		)
		(fp_rect
			(start -0.4318 0.9525)
			(end 0.4318 -0.9525)
			(stroke
				(width 0)
				(type default)
			)
			(fill no)
			(layer "F.Fab")
		)
		(pad "1" smd custom
			(at 0 -0.4445 180)
			(size 0.1524 0.1524)
			(layers "F.Cu" "F.Mask" "F.Paste")
			(net "SW_HDD6_P")
			(options
				(clearance outline)
				(anchor circle)
			)
			(primitives
				(gr_poly
					(pts
						(arc
							(start 0.3048 -0.2032)
							(mid 0.275042 -0.275042)
							(end 0.2032 -0.3048)
						)
						(arc
							(start -0.2032 -0.3048)
							(mid -0.275042 -0.275042)
							(end -0.3048 -0.2032)
						)
						(arc
							(start -0.3048 0.2032)
							(mid -0.275042 0.275042)
							(end -0.2032 0.3048)
						)
						(arc
							(start 0.2032 0.3048)
							(mid 0.275042 0.275042)
							(end 0.3048 0.2032)
						)
					)
					(width 0)
					(fill yes)
				)
			)
		)
		(pad "2" smd custom
			(at 0 0.4445 180)
			(size 0.1524 0.1524)
			(layers "F.Cu" "F.Mask" "F.Paste")
			(net "GND")
			(options
				(clearance outline)
				(anchor circle)
			)
			(primitives
				(gr_poly
					(pts
						(arc
							(start 0.3048 -0.2032)
							(mid 0.275042 -0.275042)
							(end 0.2032 -0.3048)
						)
						(arc
							(start -0.2032 -0.3048)
							(mid -0.275042 -0.275042)
							(end -0.3048 -0.2032)
						)
						(arc
							(start -0.3048 0.2032)
							(mid -0.275042 0.275042)
							(end -0.2032 0.3048)
						)
						(arc
							(start 0.2032 0.3048)
							(mid 0.275042 0.275042)
							(end 0.3048 0.2032)
						)
					)
					(width 0)
					(fill yes)
				)
			)
		)
	)
	(footprint ""
		(layer "F.Cu")
		(at 213.063582 -291.310568 180)
		(property "Reference" "C143"
			(at 0 0 180)
			(layer "F.SilkS")
			(hide yes)
			(effects
				(font
					(size 1.27 1.27)
				)
			)
		)
		(property "Value" "SC10U25V6KX-1GP"
			(at -0.0762 -5.1308 180)
			(unlocked yes)
			(layer "F.Fab")
			(hide yes)
			(effects
				(font
					(size 1.016 1.016)
					(thickness 0.1524)
				)
			)
		)
		(property "Device Type" "C1206H71"
			(at -0.127 -6.6548 180)
			(unlocked yes)
			(layer "F.Fab")
			(hide yes)
			(effects
				(font
					(size 1.016 1.016)
					(thickness 0.1524)
				)
			)
		)
		(duplicate_pad_numbers_are_jumpers no)
		(fp_line
			(start 1.016 2.2352)
			(end -1.016 2.2352)
			(stroke
				(width 0.1524)
				(type default)
			)
			(layer "F.SilkS")
		)
		(fp_line
			(start 1.016 0.8382)
			(end 1.016 2.2352)
			(stroke
				(width 0.1524)
				(type default)
			)
			(layer "F.SilkS")
		)
		(fp_line
			(start 1.016 -2.2352)
			(end 1.016 -0.8382)
			(stroke
				(width 0.1524)
				(type default)
			)
			(layer "F.SilkS")
		)
		(fp_line
			(start -1.016 2.2352)
			(end -1.016 0.8382)
			(stroke
				(width 0.1524)
				(type default)
			)
			(layer "F.SilkS")
		)
		(fp_line
			(start -1.016 -0.8382)
			(end -1.016 -2.2352)
			(stroke
				(width 0.1524)
				(type default)
			)
			(layer "F.SilkS")
		)
		(fp_line
			(start -1.016 -2.2352)
			(end 1.016 -2.2352)
			(stroke
				(width 0.1524)
				(type default)
			)
			(layer "F.SilkS")
		)
		(fp_rect
			(start -1.0922 2.3114)
			(end 1.0922 -2.3114)
			(stroke
				(width 0)
				(type default)
			)
			(fill no)
			(layer "F.CrtYd")
		)
		(fp_poly
			(pts
				(xy 1.0922 -2.3114) (xy 1.0922 2.3114) (xy -1.0922 2.3114) (xy -1.0922 -2.3114)
			)
			(stroke
				(width 0)
				(type default)
			)
			(fill no)
			(layer "F.Fab")
		)
		(pad "1" smd rect
			(at 0 -1.397 180)
			(size 1.651 1.27)
			(layers "F.Cu" "F.Mask" "F.Paste")
			(net "P12V_HDD2")
		)
		(pad "2" smd rect
			(at 0 1.397 180)
			(size 1.651 1.27)
			(layers "F.Cu" "F.Mask" "F.Paste")
			(net "GND")
		)
	)
	(footprint ""
		(layer "F.Cu")
		(at 17.500092 -361.840018)
		(property "Reference" "LED12"
			(at 0 0 0)
			(layer "F.SilkS")
			(hide yes)
			(effects
				(font
					(size 1.27 1.27)
				)
			)
		)
		(property "Value" "LED-RB-4-GP"
			(at 5.88899 1.80848 0)
			(unlocked yes)
			(layer "F.Fab")
			(hide yes)
			(effects
				(font
					(size 1.016 1.016)
					(thickness 0.1524)
				)
			)
		)
		(property "Device Type" "LED1613-4PH20"
			(at 5.88899 0.28448 0)
			(unlocked yes)
			(layer "F.Fab")
			(hide yes)
			(effects
				(font
					(size 1.016 1.016)
					(thickness 0.1524)
				)
			)
		)
		(duplicate_pad_numbers_are_jumpers no)
		(fp_line
			(start -1.4478 -0.9652)
			(end 1.4478 -0.9652)
			(stroke
				(width 0.1524)
				(type default)
			)
			(layer "F.SilkS")
		)
		(fp_line
			(start -1.4478 0.9652)
			(end -1.4478 -0.9652)
			(stroke
				(width 0.1524)
				(type default)
			)
			(layer "F.SilkS")
		)
		(fp_line
			(start -1.4478 0.9652)
			(end -1.4478 -0.9652)
			(stroke
				(width 0.508)
				(type default)
			)
			(layer "F.SilkS")
		)
		(fp_line
			(start 1.4478 -0.9652)
			(end 1.4478 0.9652)
			(stroke
				(width 0.1524)
				(type default)
			)
			(layer "F.SilkS")
		)
		(fp_line
			(start 1.4478 0.9652)
			(end -1.4478 0.9652)
			(stroke
				(width 0.1524)
				(type default)
			)
			(layer "F.SilkS")
		)
		(fp_rect
			(start -0.8001 0.6477)
			(end 0.8001 -0.6477)
			(stroke
				(width 0)
				(type default)
			)
			(fill no)
			(layer "F.CrtYd")
		)
		(fp_poly
			(pts
				(xy -1.7018 1.2192) (xy -1.7018 -0.06223) (xy -0.8001 -0.06223) (xy -0.8001 0.6477) (xy 0.8001 0.6477)
				(xy 0.8001 -0.6477) (xy -0.8001 -0.6477) (xy -0.8001 -0.0635) (xy -1.7018 -0.0635) (xy -1.7018 -1.2192)
				(xy 1.7018 -1.2192) (xy 1.7018 1.2192)
			)
			(stroke
				(width 0)
				(type default)
			)
			(fill no)
			(layer "F.CrtYd")
		)
		(fp_rect
			(start -1.7018 1.2192)
			(end 1.7018 -1.2192)
			(stroke
				(width 0)
				(type default)
			)
			(fill no)
			(layer "F.Fab")
		)
		(pad "1" smd rect
			(at -0.73025 0.4064)
			(size 0.9144 0.6096)
			(layers "F.Cu" "F.Mask" "F.Paste")
			(net "DRV_ACT_NET11")
		)
		(pad "2" smd rect
			(at -0.73025 -0.4064)
			(size 0.9144 0.6096)
			(layers "F.Cu" "F.Mask" "F.Paste")
			(net "FLT_NET_HDD11")
		)
		(pad "3" smd rect
			(at 0.73025 -0.4064)
			(size 0.9144 0.6096)
			(layers "F.Cu" "F.Mask" "F.Paste")
			(net "FLT_HDD11")
		)
		(pad "4" smd rect
			(at 0.73025 0.4064)
			(size 0.9144 0.6096)
			(layers "F.Cu" "F.Mask" "F.Paste")
			(net "DRV_ACT_11")
		)
	)
	(footprint ""
		(layer "F.Cu")
		(at 40.513 -208.28)
		(property "Reference" "C301"
			(at 0 0 0)
			(layer "F.SilkS")
			(hide yes)
			(effects
				(font
					(size 1.27 1.27)
				)
			)
		)
		(property "Value" "SCD1U10V2KX-5GP"
			(at 1.1811 -2.7051 0)
			(unlocked yes)
			(layer "F.Fab")
			(hide yes)
			(effects
				(font
					(size 1.016 1.016)
					(thickness 0.1524)
				)
			)
		)
		(property "Device Type" "C402H22"
			(at 1.1811 -4.2291 0)
			(unlocked yes)
			(layer "F.Fab")
			(hide yes)
			(effects
				(font
					(size 1.016 1.016)
					(thickness 0.1524)
				)
			)
		)
		(duplicate_pad_numbers_are_jumpers no)
		(fp_rect
			(start -0.4318 0.9525)
			(end 0.4318 -0.9525)
			(stroke
				(width 0)
				(type default)
			)
			(fill no)
			(layer "F.CrtYd")
		)
		(fp_rect
			(start -0.4318 0.9525)
			(end 0.4318 -0.9525)
			(stroke
				(width 0)
				(type default)
			)
			(fill no)
			(layer "F.Fab")
		)
		(pad "1" smd custom
			(at 0 -0.4445)
			(size 0.1524 0.1524)
			(layers "F.Cu" "F.Mask" "F.Paste")
			(net "P3V3")
			(options
				(clearance outline)
				(anchor circle)
			)
			(primitives
				(gr_poly
					(pts
						(arc
							(start 0.3048 -0.2032)
							(mid 0.275042 -0.275042)
							(end 0.2032 -0.3048)
						)
						(arc
							(start -0.2032 -0.3048)
							(mid -0.275042 -0.275042)
							(end -0.3048 -0.2032)
						)
						(arc
							(start -0.3048 0.2032)
							(mid -0.275042 0.275042)
							(end -0.2032 0.3048)
						)
						(arc
							(start 0.2032 0.3048)
							(mid 0.275042 0.275042)
							(end 0.3048 0.2032)
						)
					)
					(width 0)
					(fill yes)
				)
			)
		)
		(pad "2" smd custom
			(at 0 0.4445)
			(size 0.1524 0.1524)
			(layers "F.Cu" "F.Mask" "F.Paste")
			(net "GND")
			(options
				(clearance outline)
				(anchor circle)
			)
			(primitives
				(gr_poly
					(pts
						(arc
							(start 0.3048 -0.2032)
							(mid 0.275042 -0.275042)
							(end 0.2032 -0.3048)
						)
						(arc
							(start -0.2032 -0.3048)
							(mid -0.275042 -0.275042)
							(end -0.3048 -0.2032)
						)
						(arc
							(start -0.3048 0.2032)
							(mid -0.275042 0.275042)
							(end -0.2032 0.3048)
						)
						(arc
							(start 0.2032 0.3048)
							(mid 0.275042 0.275042)
							(end 0.3048 0.2032)
						)
					)
					(width 0)
					(fill yes)
				)
			)
		)
	)
	(footprint ""
		(layer "F.Cu")
		(at 217.854784 -167.229028 -90)
		(property "Reference" "C153"
			(at 0 0 270)
			(layer "F.SilkS")
			(hide yes)
			(effects
				(font
					(size 1.27 1.27)
				)
			)
		)
		(property "Value" "SCD01U50V2KX-1GP"
			(at 1.1811 -2.7051 270)
			(unlocked yes)
			(layer "F.Fab")
			(hide yes)
			(effects
				(font
					(size 1.016 1.016)
					(thickness 0.1524)
				)
			)
		)
		(property "Device Type" "C402H22"
			(at 1.1811 -4.2291 270)
			(unlocked yes)
			(layer "F.Fab")
			(hide yes)
			(effects
				(font
					(size 1.016 1.016)
					(thickness 0.1524)
				)
			)
		)
		(duplicate_pad_numbers_are_jumpers no)
		(fp_rect
			(start -0.4318 0.9525)
			(end 0.4318 -0.9525)
			(stroke
				(width 0)
				(type default)
			)
			(fill no)
			(layer "F.CrtYd")
		)
		(fp_rect
			(start -0.4318 0.9525)
			(end 0.4318 -0.9525)
			(stroke
				(width 0)
				(type default)
			)
			(fill no)
			(layer "F.Fab")
		)
		(pad "1" smd custom
			(at 0 -0.4445 270)
			(size 0.1524 0.1524)
			(layers "F.Cu" "F.Mask" "F.Paste")
			(net "SAS2X28_DRIVE_RX_P_B3")
			(options
				(clearance outline)
				(anchor circle)
			)
			(primitives
				(gr_poly
					(pts
						(arc
							(start 0.3048 -0.2032)
							(mid 0.275042 -0.275042)
							(end 0.2032 -0.3048)
						)
						(arc
							(start -0.2032 -0.3048)
							(mid -0.275042 -0.275042)
							(end -0.3048 -0.2032)
						)
						(arc
							(start -0.3048 0.2032)
							(mid -0.275042 0.275042)
							(end -0.2032 0.3048)
						)
						(arc
							(start 0.2032 0.3048)
							(mid 0.275042 0.275042)
							(end 0.3048 0.2032)
						)
					)
					(width 0)
					(fill yes)
				)
			)
		)
		(pad "2" smd custom
			(at 0 0.4445 270)
			(size 0.1524 0.1524)
			(layers "F.Cu" "F.Mask" "F.Paste")
			(net "SAS2X28_B_HDD3_RX_+")
			(options
				(clearance outline)
				(anchor circle)
			)
			(primitives
				(gr_poly
					(pts
						(arc
							(start 0.3048 -0.2032)
							(mid 0.275042 -0.275042)
							(end 0.2032 -0.3048)
						)
						(arc
							(start -0.2032 -0.3048)
							(mid -0.275042 -0.275042)
							(end -0.3048 -0.2032)
						)
						(arc
							(start -0.3048 0.2032)
							(mid -0.275042 0.275042)
							(end -0.2032 0.3048)
						)
						(arc
							(start 0.2032 0.3048)
							(mid 0.275042 0.275042)
							(end 0.3048 0.2032)
						)
					)
					(width 0)
					(fill yes)
				)
			)
		)
	)
)
